(kicad_pcb
	(version 20260206)
	(generator "pcbnew")
	(generator_version "10.0")
	(general
		(thickness 1.6)
		(legacy_teardrops no)
	)
	(paper "A4")
	(title_block
		(title "Wiwynn_Tioga_Pass_MB.brd")
		(comment 1 "Tioga Pass / footprints 2733-2740 of 4770")
	)
	(layers
		(0 "F.Cu" signal "TOP")
		(4 "In1.Cu" signal "L2GND")
		(6 "In2.Cu" signal "L3")
		(8 "In3.Cu" signal "L4GND")
		(10 "In4.Cu" signal "L5")
		(12 "In5.Cu" signal "L6GND")
		(14 "In6.Cu" signal "L7VCC")
		(16 "In7.Cu" signal "L8VCC")
		(18 "In8.Cu" signal "L9GND")
		(20 "In9.Cu" signal "L10")
		(22 "In10.Cu" signal "L11GND")
		(24 "In11.Cu" signal "L12")
		(26 "In12.Cu" signal "L13GND")
		(2 "B.Cu" signal "BOTTOM")
		(9 "F.Adhes" user "F.Adhesive")
		(11 "B.Adhes" user "B.Adhesive")
		(13 "F.Paste" user "Package Geometry/Pastemask Top")
		(15 "B.Paste" user "Package Geometry/Pastemask Bottom")
		(5 "F.SilkS" user "Ref Des/Silkscreen Top")
		(7 "B.SilkS" user "Ref Des/Silkscreen Bottom")
		(1 "F.Mask" user "Board Geometry/Soldermask Top")
		(3 "B.Mask" user "Board Geometry/Soldermask Bottom")
		(17 "Dwgs.User" user "User.Drawings")
		(19 "Cmts.User" user "User.Comments")
		(21 "Eco1.User" user "User.Eco1")
		(23 "Eco2.User" user "User.Eco2")
		(25 "Edge.Cuts" user "Board Geometry/Outline")
		(27 "Margin" user)
		(31 "F.CrtYd" user "Package Geometry/Place Bound Top")
		(29 "B.CrtYd" user "Package Geometry/Place Bound Bottom")
		(35 "F.Fab" user "Ref Des/Assembly Top")
		(33 "B.Fab" user "Ref Des/Assembly Bottom")
	)
	(footprint ""
		(layer "B.Cu")
		(at 417.895024 -140.843 180)
		(property "Reference" "R2L23"
			(at 0 0 0)
			(layer "B.SilkS")
			(hide yes)
			(effects
				(font
					(size 1.27 1.27)
				)
				(justify mirror)
			)
		)
		(property "Value" ""
			(at 0 0 0)
			(layer "B.Fab")
			(effects
				(font
					(size 1.27 1.27)
				)
				(justify mirror)
			)
		)
		(duplicate_pad_numbers_are_jumpers no)
		(fp_poly
			(pts
				(xy 0.2794 -0.1016) (xy -0.2794 -0.1016) (xy -0.2794 0.9906) (xy 0.2794 0.9906)
			)
			(stroke
				(width 0)
				(type default)
			)
			(fill no)
			(layer "B.CrtYd")
		)
		(fp_line
			(start 0.2794 0.9906)
			(end -0.2794 0.9906)
			(stroke
				(width 0.1)
				(type default)
			)
			(layer "B.Fab")
		)
		(fp_line
			(start 0.2794 -0.1016)
			(end 0.2794 0.9906)
			(stroke
				(width 0.1)
				(type default)
			)
			(layer "B.Fab")
		)
		(fp_line
			(start -0.2794 0.9906)
			(end -0.2794 -0.1016)
			(stroke
				(width 0.1)
				(type default)
			)
			(layer "B.Fab")
		)
		(fp_line
			(start -0.2794 -0.1016)
			(end 0.2794 -0.1016)
			(stroke
				(width 0.1)
				(type default)
			)
			(layer "B.Fab")
		)
		(pad "1" smd rect
			(at 0 0)
			(size 0.508 0.508)
			(layers "B.Cu" "B.Mask" "B.Paste")
			(net "P3V3")
		)
		(pad "2" smd rect
			(at 0 0.889)
			(size 0.508 0.508)
			(layers "B.Cu" "B.Mask" "B.Paste")
			(net "PU_DATAIN1_SATA_1_R")
		)
		(zone
			(layer "B.Cu")
			(hatch none 0.5)
			(connect_pads
				(clearance 0)
			)
			(min_thickness 0.25)
			(keepout
				(tracks not_allowed)
				(vias allowed)
				(pads allowed)
				(copperpour not_allowed)
				(footprints allowed)
			)
			(placement
				(enabled no)
				(sheetname "")
			)
			(fill
				(thermal_gap 0.5)
				(thermal_bridge_width 0.5)
				(island_removal_mode 0)
			)
			(polygon
				(pts
					(xy 417.641024 -141.478) (xy 418.149024 -141.478) (xy 418.149024 -141.097) (xy 417.641024 -141.097)
				)
			)
		)
		(zone
			(layer "B.Cu")
			(hatch none 0.5)
			(connect_pads
				(clearance 0)
			)
			(min_thickness 0.25)
			(keepout
				(tracks allowed)
				(vias not_allowed)
				(pads allowed)
				(copperpour not_allowed)
				(footprints allowed)
			)
			(placement
				(enabled no)
				(sheetname "")
			)
			(fill
				(thermal_gap 0.5)
				(thermal_bridge_width 0.5)
				(island_removal_mode 0)
			)
			(polygon
				(pts
					(xy 417.641024 -141.097) (xy 418.149024 -141.097) (xy 418.149024 -141.478) (xy 417.641024 -141.478)
				)
			)
		)
	)
	(footprint ""
		(layer "B.Cu")
		(at 14.478 -87.63)
		(property "Reference" "R9P3"
			(at 0 0 0)
			(layer "B.SilkS")
			(hide yes)
			(effects
				(font
					(size 1.27 1.27)
				)
				(justify mirror)
			)
		)
		(property "Value" ""
			(at 0 0 0)
			(layer "B.Fab")
			(effects
				(font
					(size 1.27 1.27)
				)
				(justify mirror)
			)
		)
		(duplicate_pad_numbers_are_jumpers no)
		(fp_poly
			(pts
				(xy 0.2794 -0.1016) (xy -0.2794 -0.1016) (xy -0.2794 0.9906) (xy 0.2794 0.9906)
			)
			(stroke
				(width 0)
				(type default)
			)
			(fill no)
			(layer "B.CrtYd")
		)
		(fp_line
			(start -0.2794 -0.1016)
			(end 0.2794 -0.1016)
			(stroke
				(width 0.1)
				(type default)
			)
			(layer "B.Fab")
		)
		(fp_line
			(start -0.2794 0.9906)
			(end -0.2794 -0.1016)
			(stroke
				(width 0.1)
				(type default)
			)
			(layer "B.Fab")
		)
		(fp_line
			(start 0.2794 -0.1016)
			(end 0.2794 0.9906)
			(stroke
				(width 0.1)
				(type default)
			)
			(layer "B.Fab")
		)
		(fp_line
			(start 0.2794 0.9906)
			(end -0.2794 0.9906)
			(stroke
				(width 0.1)
				(type default)
			)
			(layer "B.Fab")
		)
		(pad "1" smd rect
			(at 0 0 180)
			(size 0.508 0.508)
			(layers "B.Cu" "B.Mask" "B.Paste")
			(net "IRQ_PVCCIN_CPU1_VRHOT_LVC3_R_N")
		)
		(pad "2" smd rect
			(at 0 0.889 180)
			(size 0.508 0.508)
			(layers "B.Cu" "B.Mask" "B.Paste")
			(net "IRQ_PVCCIN_CPU1_VRHOT_LVC3_N")
		)
		(zone
			(layer "B.Cu")
			(hatch none 0.5)
			(connect_pads
				(clearance 0)
			)
			(min_thickness 0.25)
			(keepout
				(tracks allowed)
				(vias not_allowed)
				(pads allowed)
				(copperpour not_allowed)
				(footprints allowed)
			)
			(placement
				(enabled no)
				(sheetname "")
			)
			(fill
				(thermal_gap 0.5)
				(thermal_bridge_width 0.5)
				(island_removal_mode 0)
			)
			(polygon
				(pts
					(xy 14.732 -87.376) (xy 14.224 -87.376) (xy 14.224 -86.995) (xy 14.732 -86.995)
				)
			)
		)
		(zone
			(layer "B.Cu")
			(hatch none 0.5)
			(connect_pads
				(clearance 0)
			)
			(min_thickness 0.25)
			(keepout
				(tracks not_allowed)
				(vias allowed)
				(pads allowed)
				(copperpour not_allowed)
				(footprints allowed)
			)
			(placement
				(enabled no)
				(sheetname "")
			)
			(fill
				(thermal_gap 0.5)
				(thermal_bridge_width 0.5)
				(island_removal_mode 0)
			)
			(polygon
				(pts
					(xy 14.732 -86.995) (xy 14.224 -86.995) (xy 14.224 -87.376) (xy 14.732 -87.376)
				)
			)
		)
	)
	(footprint ""
		(layer "B.Cu")
		(at 183.3626 -134.5438 90)
		(property "Reference" "C6M3"
			(at -1.47828 0.78994 180)
			(unlocked yes)
			(layer "B.SilkS")
			(effects
				(font
					(size 0.4064 0.254)
					(thickness 0.1524)
				)
				(justify mirror)
			)
		)
		(property "Value" ""
			(at 0 0 90)
			(layer "B.Fab")
			(effects
				(font
					(size 1.27 1.27)
				)
				(justify mirror)
			)
		)
		(duplicate_pad_numbers_are_jumpers no)
		(fp_poly
			(pts
				(xy 0.7239 -0.2159) (xy -0.7239 -0.2159) (xy -0.7239 1.9939) (xy 0.7239 1.9939)
			)
			(stroke
				(width 0)
				(type default)
			)
			(fill no)
			(layer "B.CrtYd")
		)
		(fp_line
			(start 0.7239 -0.2159)
			(end 0.7239 1.9939)
			(stroke
				(width 0.1)
				(type default)
			)
			(layer "B.Fab")
		)
		(fp_line
			(start -0.7239 -0.2159)
			(end 0.7239 -0.2159)
			(stroke
				(width 0.1)
				(type default)
			)
			(layer "B.Fab")
		)
		(fp_line
			(start 0.7239 1.9939)
			(end -0.7239 1.9939)
			(stroke
				(width 0.1)
				(type default)
			)
			(layer "B.Fab")
		)
		(fp_line
			(start -0.7239 1.9939)
			(end -0.7239 -0.2159)
			(stroke
				(width 0.1)
				(type default)
			)
			(layer "B.Fab")
		)
		(pad "1" smd rect
			(at 0 0 270)
			(size 1.27 1.016)
			(layers "B.Cu" "B.Mask" "B.Paste")
			(net "VR_FET_SW_P12V_STBY_PVPP_KLM")
		)
		(pad "2" smd rect
			(at 0 1.778 270)
			(size 1.27 1.016)
			(layers "B.Cu" "B.Mask" "B.Paste")
			(net "GND")
		)
		(zone
			(layer "B.Cu")
			(hatch none 0.5)
			(connect_pads
				(clearance 0)
			)
			(min_thickness 0.25)
			(keepout
				(tracks not_allowed)
				(vias allowed)
				(pads allowed)
				(copperpour not_allowed)
				(footprints allowed)
			)
			(placement
				(enabled no)
				(sheetname "")
			)
			(fill
				(thermal_gap 0.5)
				(thermal_bridge_width 0.5)
				(island_removal_mode 0)
			)
			(polygon
				(pts
					(xy 183.8706 -135.1788) (xy 183.8706 -133.9088) (xy 184.6326 -133.9088) (xy 184.6326 -135.1788)
				)
			)
		)
	)
	(footprint ""
		(layer "B.Cu")
		(at 374.777 -100.3046 90)
		(property "Reference" "R3N4"
			(at 0 0 90)
			(layer "B.SilkS")
			(hide yes)
			(effects
				(font
					(size 1.27 1.27)
				)
				(justify mirror)
			)
		)
		(property "Value" ""
			(at 0 0 90)
			(layer "B.Fab")
			(effects
				(font
					(size 1.27 1.27)
				)
				(justify mirror)
			)
		)
		(duplicate_pad_numbers_are_jumpers no)
		(fp_poly
			(pts
				(xy 0.2794 -0.1016) (xy -0.2794 -0.1016) (xy -0.2794 0.9906) (xy 0.2794 0.9906)
			)
			(stroke
				(width 0)
				(type default)
			)
			(fill no)
			(layer "B.CrtYd")
		)
		(fp_line
			(start 0.2794 -0.1016)
			(end 0.2794 0.9906)
			(stroke
				(width 0.1)
				(type default)
			)
			(layer "B.Fab")
		)
		(fp_line
			(start -0.2794 -0.1016)
			(end 0.2794 -0.1016)
			(stroke
				(width 0.1)
				(type default)
			)
			(layer "B.Fab")
		)
		(fp_line
			(start 0.2794 0.9906)
			(end -0.2794 0.9906)
			(stroke
				(width 0.1)
				(type default)
			)
			(layer "B.Fab")
		)
		(fp_line
			(start -0.2794 0.9906)
			(end -0.2794 -0.1016)
			(stroke
				(width 0.1)
				(type default)
			)
			(layer "B.Fab")
		)
		(pad "1" smd rect
			(at 0 0 270)
			(size 0.508 0.508)
			(layers "B.Cu" "B.Mask" "B.Paste")
			(net "P3V3_RTC_STBY")
		)
		(pad "2" smd rect
			(at 0 0.889 270)
			(size 0.508 0.508)
			(layers "B.Cu" "B.Mask" "B.Paste")
			(net "RST_SRTCRST_N")
		)
		(zone
			(layer "B.Cu")
			(hatch none 0.5)
			(connect_pads
				(clearance 0)
			)
			(min_thickness 0.25)
			(keepout
				(tracks allowed)
				(vias not_allowed)
				(pads allowed)
				(copperpour not_allowed)
				(footprints allowed)
			)
			(placement
				(enabled no)
				(sheetname "")
			)
			(fill
				(thermal_gap 0.5)
				(thermal_bridge_width 0.5)
				(island_removal_mode 0)
			)
			(polygon
				(pts
					(xy 375.031 -100.5586) (xy 375.031 -100.0506) (xy 375.412 -100.0506) (xy 375.412 -100.5586)
				)
			)
		)
		(zone
			(layer "B.Cu")
			(hatch none 0.5)
			(connect_pads
				(clearance 0)
			)
			(min_thickness 0.25)
			(keepout
				(tracks not_allowed)
				(vias allowed)
				(pads allowed)
				(copperpour not_allowed)
				(footprints allowed)
			)
			(placement
				(enabled no)
				(sheetname "")
			)
			(fill
				(thermal_gap 0.5)
				(thermal_bridge_width 0.5)
				(island_removal_mode 0)
			)
			(polygon
				(pts
					(xy 375.412 -100.5586) (xy 375.412 -100.0506) (xy 375.031 -100.0506) (xy 375.031 -100.5586)
				)
			)
		)
	)
	(footprint ""
		(layer "B.Cu")
		(at -2.5146 -128.6002 -90)
		(property "Reference" "R9M6"
			(at 0 0 90)
			(layer "B.SilkS")
			(hide yes)
			(effects
				(font
					(size 1.27 1.27)
				)
				(justify mirror)
			)
		)
		(property "Value" ""
			(at 0 0 90)
			(layer "B.Fab")
			(effects
				(font
					(size 1.27 1.27)
				)
				(justify mirror)
			)
		)
		(duplicate_pad_numbers_are_jumpers no)
		(fp_rect
			(start 0.2794 0.9906)
			(end -0.2794 -0.1016)
			(stroke
				(width 0)
				(type default)
			)
			(fill no)
			(layer "B.CrtYd")
		)
		(fp_line
			(start -0.2794 0.9906)
			(end -0.2794 -0.1016)
			(stroke
				(width 0.1)
				(type default)
			)
			(layer "B.Fab")
		)
		(fp_line
			(start 0.2794 0.9906)
			(end -0.2794 0.9906)
			(stroke
				(width 0.1)
				(type default)
			)
			(layer "B.Fab")
		)
		(fp_line
			(start -0.2794 -0.1016)
			(end 0.2794 -0.1016)
			(stroke
				(width 0.1)
				(type default)
			)
			(layer "B.Fab")
		)
		(fp_line
			(start 0.2794 -0.1016)
			(end 0.2794 0.9906)
			(stroke
				(width 0.1)
				(type default)
			)
			(layer "B.Fab")
		)
		(pad "1" smd rect
			(at 0 0 90)
			(size 0.508 0.508)
			(layers "B.Cu" "B.Mask" "B.Paste")
			(net "PVCCIO_CPU1")
		)
		(pad "2" smd rect
			(at 0 0.889 90)
			(size 0.508 0.508)
			(layers "B.Cu" "B.Mask" "B.Paste")
			(net "SVID_CLK1_CPU1_R")
		)
		(zone
			(layer "B.Cu")
			(hatch none 0.5)
			(connect_pads
				(clearance 0)
			)
			(min_thickness 0.25)
			(keepout
				(tracks not_allowed)
				(vias allowed)
				(pads allowed)
				(copperpour not_allowed)
				(footprints allowed)
			)
			(placement
				(enabled no)
				(sheetname "")
			)
			(fill
				(thermal_gap 0.5)
				(thermal_bridge_width 0.5)
				(island_removal_mode 0)
			)
			(polygon
				(pts
					(xy -3.1496 -128.3462) (xy -2.7686 -128.3462) (xy -2.7686 -128.8542) (xy -3.1496 -128.8542)
				)
			)
		)
		(zone
			(layer "B.Cu")
			(hatch none 0.5)
			(connect_pads
				(clearance 0)
			)
			(min_thickness 0.25)
			(keepout
				(tracks allowed)
				(vias not_allowed)
				(pads allowed)
				(copperpour not_allowed)
				(footprints allowed)
			)
			(placement
				(enabled no)
				(sheetname "")
			)
			(fill
				(thermal_gap 0.5)
				(thermal_bridge_width 0.5)
				(island_removal_mode 0)
			)
			(polygon
				(pts
					(xy -3.1496 -128.3462) (xy -2.7686 -128.3462) (xy -2.7686 -128.8542) (xy -3.1496 -128.8542)
				)
			)
		)
	)
	(footprint ""
		(layer "B.Cu")
		(at 494.75136 -126.5174 -90)
		(property "Reference" "U1M1"
			(at 0 0 90)
			(layer "B.SilkS")
			(hide yes)
			(effects
				(font
					(size 1.27 1.27)
				)
				(justify mirror)
			)
		)
		(property "Value" ""
			(at 0 0 90)
			(layer "B.Fab")
			(effects
				(font
					(size 1.27 1.27)
				)
				(justify mirror)
			)
		)
		(duplicate_pad_numbers_are_jumpers no)
		(fp_circle
			(center 0.813308 -0.4826)
			(end 0.813308 -0.6096)
			(stroke
				(width 0.254)
				(type default)
			)
			(fill no)
			(layer "B.SilkS")
		)
		(fp_poly
			(pts
				(xy -0.21463 -0.450088) (xy -1.56337 -0.450088) (xy -1.56337 1.75006) (xy -0.21463 1.75006)
			)
			(stroke
				(width 0)
				(type default)
			)
			(fill no)
			(layer "B.CrtYd")
		)
		(fp_line
			(start -1.56337 1.75006)
			(end -0.21463 1.75006)
			(stroke
				(width 0.1)
				(type default)
			)
			(layer "B.Fab")
		)
		(fp_line
			(start -0.21463 1.75006)
			(end -0.21463 -0.450088)
			(stroke
				(width 0.1)
				(type default)
			)
			(layer "B.Fab")
		)
		(fp_line
			(start -1.56337 -0.450088)
			(end -1.56337 1.75006)
			(stroke
				(width 0.1)
				(type default)
			)
			(layer "B.Fab")
		)
		(fp_line
			(start -0.21463 -0.450088)
			(end -1.56337 -0.450088)
			(stroke
				(width 0.1)
				(type default)
			)
			(layer "B.Fab")
		)
		(fp_circle
			(center -0.544322 -0.583946)
			(end -0.544322 -0.710946)
			(stroke
				(width 0.254)
				(type default)
			)
			(fill no)
			(layer "B.Fab")
		)
		(pad "1" smd rect
			(at 0 0 90)
			(size 1.016 0.381)
			(layers "B.Cu" "B.Mask" "B.Paste")
			(net "LED_SATA_ACT_R_N")
		)
		(pad "2" smd rect
			(at 0 0.649986 90)
			(size 1.016 0.381)
			(layers "B.Cu" "B.Mask" "B.Paste")
			(net "LED_SAS_ACT_R_N")
		)
		(pad "3" smd rect
			(at 0 1.299972 90)
			(size 1.016 0.381)
			(layers "B.Cu" "B.Mask" "B.Paste")
			(net "GND")
		)
		(pad "4" smd rect
			(at -1.778 1.299972 90)
			(size 1.016 0.381)
			(layers "B.Cu" "B.Mask" "B.Paste")
			(net "FP_LED_HDD_ACTIVITY_AND_N")
		)
		(pad "5" smd rect
			(at -1.778 0 90)
			(size 1.016 0.381)
			(layers "B.Cu" "B.Mask" "B.Paste")
			(net "P3V3")
		)
	)
	(footprint ""
		(layer "B.Cu")
		(at 93.548454 -77.82814)
		(property "Reference" "C8P21"
			(at 0 0 0)
			(layer "B.SilkS")
			(hide yes)
			(effects
				(font
					(size 1.27 1.27)
				)
				(justify mirror)
			)
		)
		(property "Value" ""
			(at 0 0 0)
			(layer "B.Fab")
			(effects
				(font
					(size 1.27 1.27)
				)
				(justify mirror)
			)
		)
		(duplicate_pad_numbers_are_jumpers no)
		(fp_poly
			(pts
				(xy 0.7239 -0.2159) (xy -0.7239 -0.2159) (xy -0.7239 1.9939) (xy 0.7239 1.9939)
			)
			(stroke
				(width 0)
				(type default)
			)
			(fill no)
			(layer "B.CrtYd")
		)
		(fp_line
			(start -0.7239 -0.2159)
			(end 0.7239 -0.2159)
			(stroke
				(width 0.1)
				(type default)
			)
			(layer "B.Fab")
		)
		(fp_line
			(start -0.7239 1.9939)
			(end -0.7239 -0.2159)
			(stroke
				(width 0.1)
				(type default)
			)
			(layer "B.Fab")
		)
		(fp_line
			(start 0.7239 -0.2159)
			(end 0.7239 1.9939)
			(stroke
				(width 0.1)
				(type default)
			)
			(layer "B.Fab")
		)
		(fp_line
			(start 0.7239 1.9939)
			(end -0.7239 1.9939)
			(stroke
				(width 0.1)
				(type default)
			)
			(layer "B.Fab")
		)
		(pad "1" smd rect
			(at 0 0 180)
			(size 1.27 1.016)
			(layers "B.Cu" "B.Mask" "B.Paste")
			(net "PVCCIN_CPU1")
		)
		(pad "2" smd rect
			(at 0 1.778 180)
			(size 1.27 1.016)
			(layers "B.Cu" "B.Mask" "B.Paste")
			(net "GND")
		)
		(zone
			(layer "B.Cu")
			(hatch none 0.5)
			(connect_pads
				(clearance 0)
			)
			(min_thickness 0.25)
			(keepout
				(tracks not_allowed)
				(vias allowed)
				(pads allowed)
				(copperpour not_allowed)
				(footprints allowed)
			)
			(placement
				(enabled no)
				(sheetname "")
			)
			(fill
				(thermal_gap 0.5)
				(thermal_bridge_width 0.5)
				(island_removal_mode 0)
			)
			(polygon
				(pts
					(xy 94.183454 -77.32014) (xy 92.913454 -77.32014) (xy 92.913454 -76.55814) (xy 94.183454 -76.55814)
				)
			)
		)
	)
	(footprint ""
		(layer "B.Cu")
		(at 267.692886 -77.82814)
		(property "Reference" "C5P22"
			(at 0 0 0)
			(layer "B.SilkS")
			(hide yes)
			(effects
				(font
					(size 1.27 1.27)
				)
				(justify mirror)
			)
		)
		(property "Value" ""
			(at 0 0 0)
			(layer "B.Fab")
			(effects
				(font
					(size 1.27 1.27)
				)
				(justify mirror)
			)
		)
		(duplicate_pad_numbers_are_jumpers no)
		(fp_poly
			(pts
				(xy 0.7239 -0.2159) (xy -0.7239 -0.2159) (xy -0.7239 1.9939) (xy 0.7239 1.9939)
			)
			(stroke
				(width 0)
				(type default)
			)
			(fill no)
			(layer "B.CrtYd")
		)
		(fp_line
			(start -0.7239 -0.2159)
			(end 0.7239 -0.2159)
			(stroke
				(width 0.1)
				(type default)
			)
			(layer "B.Fab")
		)
		(fp_line
			(start -0.7239 1.9939)
			(end -0.7239 -0.2159)
			(stroke
				(width 0.1)
				(type default)
			)
			(layer "B.Fab")
		)
		(fp_line
			(start 0.7239 -0.2159)
			(end 0.7239 1.9939)
			(stroke
				(width 0.1)
				(type default)
			)
			(layer "B.Fab")
		)
		(fp_line
			(start 0.7239 1.9939)
			(end -0.7239 1.9939)
			(stroke
				(width 0.1)
				(type default)
			)
			(layer "B.Fab")
		)
		(pad "1" smd rect
			(at 0 0 180)
			(size 1.27 1.016)
			(layers "B.Cu" "B.Mask" "B.Paste")
			(net "PVCCIN_CPU0")
		)
		(pad "2" smd rect
			(at 0 1.778 180)
			(size 1.27 1.016)
			(layers "B.Cu" "B.Mask" "B.Paste")
			(net "GND")
		)
		(zone
			(layer "B.Cu")
			(hatch none 0.5)
			(connect_pads
				(clearance 0)
			)
			(min_thickness 0.25)
			(keepout
				(tracks not_allowed)
				(vias allowed)
				(pads allowed)
				(copperpour not_allowed)
				(footprints allowed)
			)
			(placement
				(enabled no)
				(sheetname "")
			)
			(fill
				(thermal_gap 0.5)
				(thermal_bridge_width 0.5)
				(island_removal_mode 0)
			)
			(polygon
				(pts
					(xy 268.327886 -77.32014) (xy 267.057886 -77.32014) (xy 267.057886 -76.55814) (xy 268.327886 -76.55814)
				)
			)
		)
	)
)
